(kicad_pcb
	(version 20260206)
	(generator "pcbnew")
	(generator_version "10.0")
	(general
		(thickness 1.6)
		(legacy_teardrops no)
	)
	(paper "A4")
	(title_block
		(title "Bryce Canyon_SCC_16316-1_OCP.brd")
		(comment 1 "Bryce Canyon / footprints 1065-1071 of 1561")
	)
	(layers
		(0 "F.Cu" signal "TOP")
		(4 "In1.Cu" signal "L2GND")
		(6 "In2.Cu" signal "L3")
		(8 "In3.Cu" signal "L4VCC")
		(10 "In4.Cu" signal "L5VCC")
		(12 "In5.Cu" signal "L6")
		(14 "In6.Cu" signal "L7GND")
		(2 "B.Cu" signal "BOTTOM")
		(9 "F.Adhes" user "F.Adhesive")
		(11 "B.Adhes" user "B.Adhesive")
		(13 "F.Paste" user "Package Geometry/Pastemask Top")
		(15 "B.Paste" user "Package Geometry/Pastemask Bottom")
		(5 "F.SilkS" user "Ref Des/Silkscreen Top")
		(7 "B.SilkS" user "Ref Des/Silkscreen Bottom")
		(1 "F.Mask" user "Board Geometry/Soldermask Top")
		(3 "B.Mask" user "Board Geometry/Soldermask Bottom")
		(17 "Dwgs.User" user "User.Drawings")
		(19 "Cmts.User" user "User.Comments")
		(21 "Eco1.User" user "User.Eco1")
		(23 "Eco2.User" user "User.Eco2")
		(25 "Edge.Cuts" user "Board Geometry/Outline")
		(27 "Margin" user)
		(31 "F.CrtYd" user "Package Geometry/Place Bound Top")
		(29 "B.CrtYd" user "Package Geometry/Place Bound Bottom")
		(35 "F.Fab" user "Ref Des/Assembly Top")
		(33 "B.Fab" user "Ref Des/Assembly Bottom")
	)
	(footprint ""
		(layer "B.Cu")
		(at 186.931808 -40.72001 -90)
		(property "Reference" "R191"
			(at 0 0 90)
			(layer "B.SilkS")
			(hide yes)
			(effects
				(font
					(size 1.27 1.27)
				)
				(justify mirror)
			)
		)
		(property "Value" "2K2R2F-GP"
			(at -0.064008 -3.993896 270)
			(unlocked yes)
			(layer "B.Fab")
			(hide yes)
			(effects
				(font
					(size 1.016 1.016)
					(thickness 0.1524)
				)
				(justify mirror)
			)
		)
		(property "Device Type" "R402H16"
			(at -0.064008 -5.517896 270)
			(unlocked yes)
			(layer "B.Fab")
			(hide yes)
			(effects
				(font
					(size 1.016 1.016)
					(thickness 0.1524)
				)
				(justify mirror)
			)
		)
		(duplicate_pad_numbers_are_jumpers no)
		(fp_line
			(start -0.508 -0.9398)
			(end 0.508 -0.9398)
			(stroke
				(width 0.1524)
				(type default)
			)
			(layer "B.SilkS")
		)
		(fp_line
			(start 0.508 -0.9398)
			(end 0.508 0.9398)
			(stroke
				(width 0.1524)
				(type default)
			)
			(layer "B.SilkS")
		)
		(fp_rect
			(start 0.508 0.9398)
			(end -0.508 -0.9398)
			(stroke
				(width 0)
				(type default)
			)
			(fill no)
			(layer "B.CrtYd")
		)
		(fp_rect
			(start 0.508 0.9398)
			(end -0.508 -0.9398)
			(stroke
				(width 0)
				(type default)
			)
			(fill no)
			(layer "B.Fab")
		)
		(pad "1" smd custom
			(at 0 -0.4445 90)
			(size 0.1397 0.1397)
			(layers "B.Cu" "B.Mask" "B.Paste")
			(net "P1V8_C")
			(options
				(clearance outline)
				(anchor circle)
			)
			(primitives
				(gr_poly
					(pts
						(arc
							(start -0.1778 0.2794)
							(mid -0.249642 0.249642)
							(end -0.2794 0.1778)
						)
						(arc
							(start -0.2794 -0.1778)
							(mid -0.249642 -0.249642)
							(end -0.1778 -0.2794)
						)
						(arc
							(start 0.1778 -0.2794)
							(mid 0.249642 -0.249642)
							(end 0.2794 -0.1778)
						)
						(arc
							(start 0.2794 0.1778)
							(mid 0.249642 0.249642)
							(end 0.1778 0.2794)
						)
					)
					(width 0)
					(fill yes)
				)
			)
		)
		(pad "2" smd custom
			(at 0 0.4445 90)
			(size 0.1397 0.1397)
			(layers "B.Cu" "B.Mask" "B.Paste")
			(net "I2C_IOC_4_SDA")
			(options
				(clearance outline)
				(anchor circle)
			)
			(primitives
				(gr_poly
					(pts
						(arc
							(start -0.1778 0.2794)
							(mid -0.249642 0.249642)
							(end -0.2794 0.1778)
						)
						(arc
							(start -0.2794 -0.1778)
							(mid -0.249642 -0.249642)
							(end -0.1778 -0.2794)
						)
						(arc
							(start 0.1778 -0.2794)
							(mid 0.249642 -0.249642)
							(end 0.2794 -0.1778)
						)
						(arc
							(start 0.2794 0.1778)
							(mid 0.249642 0.249642)
							(end 0.1778 0.2794)
						)
					)
					(width 0)
					(fill yes)
				)
			)
		)
	)
	(footprint ""
		(layer "B.Cu")
		(at 163.3093 -34.2646 90)
		(property "Reference" "C375"
			(at 0 0 90)
			(layer "B.SilkS")
			(hide yes)
			(effects
				(font
					(size 1.27 1.27)
				)
				(justify mirror)
			)
		)
		(property "Value" "SCD1U16V2KX-3GP"
			(at -1.1811 -2.7051 90)
			(unlocked yes)
			(layer "B.Fab")
			(hide yes)
			(effects
				(font
					(size 1.016 1.016)
					(thickness 0.1524)
				)
				(justify mirror)
			)
		)
		(property "Device Type" "C402H22"
			(at -1.1811 -4.2291 90)
			(unlocked yes)
			(layer "B.Fab")
			(hide yes)
			(effects
				(font
					(size 1.016 1.016)
					(thickness 0.1524)
				)
				(justify mirror)
			)
		)
		(duplicate_pad_numbers_are_jumpers no)
		(fp_rect
			(start 0.4318 0.9525)
			(end -0.4318 -0.9525)
			(stroke
				(width 0)
				(type default)
			)
			(fill no)
			(layer "B.CrtYd")
		)
		(fp_rect
			(start 0.4318 0.9525)
			(end -0.4318 -0.9525)
			(stroke
				(width 0)
				(type default)
			)
			(fill no)
			(layer "B.Fab")
		)
		(pad "1" smd custom
			(at 0 -0.4445 270)
			(size 0.1524 0.1524)
			(layers "B.Cu" "B.Mask" "B.Paste")
			(net "SAS0_VDDH")
			(options
				(clearance outline)
				(anchor circle)
			)
			(primitives
				(gr_poly
					(pts
						(arc
							(start 0.3048 0.2032)
							(mid 0.275042 0.275042)
							(end 0.2032 0.3048)
						)
						(arc
							(start -0.2032 0.3048)
							(mid -0.275042 0.275042)
							(end -0.3048 0.2032)
						)
						(arc
							(start -0.3048 -0.2032)
							(mid -0.275042 -0.275042)
							(end -0.2032 -0.3048)
						)
						(arc
							(start 0.2032 -0.3048)
							(mid 0.275042 -0.275042)
							(end 0.3048 -0.2032)
						)
					)
					(width 0)
					(fill yes)
				)
			)
		)
		(pad "2" smd custom
			(at 0 0.4445 270)
			(size 0.1524 0.1524)
			(layers "B.Cu" "B.Mask" "B.Paste")
			(net "GND")
			(options
				(clearance outline)
				(anchor circle)
			)
			(primitives
				(gr_poly
					(pts
						(arc
							(start 0.3048 0.2032)
							(mid 0.275042 0.275042)
							(end 0.2032 0.3048)
						)
						(arc
							(start -0.2032 0.3048)
							(mid -0.275042 0.275042)
							(end -0.3048 0.2032)
						)
						(arc
							(start -0.3048 -0.2032)
							(mid -0.275042 -0.275042)
							(end -0.2032 -0.3048)
						)
						(arc
							(start 0.2032 -0.3048)
							(mid 0.275042 -0.275042)
							(end 0.3048 -0.2032)
						)
					)
					(width 0)
					(fill yes)
				)
			)
		)
	)
	(footprint ""
		(layer "B.Cu")
		(at 116.6241 -57.4802)
		(property "Reference" "C265"
			(at 0 0 0)
			(layer "B.SilkS")
			(hide yes)
			(effects
				(font
					(size 1.27 1.27)
				)
				(justify mirror)
			)
		)
		(property "Value" "SCD1U6D3V1KX-GP"
			(at 2.8321 -1.7399 0)
			(unlocked yes)
			(layer "B.Fab")
			(hide yes)
			(effects
				(font
					(size 1.016 1.016)
					(thickness 0.1524)
				)
				(justify mirror)
			)
		)
		(property "Device Type" "C0201H13"
			(at 2.8321 -3.2639 0)
			(unlocked yes)
			(layer "B.Fab")
			(hide yes)
			(effects
				(font
					(size 1.016 1.016)
					(thickness 0.1524)
				)
				(justify mirror)
			)
		)
		(duplicate_pad_numbers_are_jumpers no)
		(fp_rect
			(start 0.2794 0.6477)
			(end -0.2794 -0.6477)
			(stroke
				(width 0)
				(type default)
			)
			(fill no)
			(layer "B.CrtYd")
		)
		(fp_rect
			(start 0.2794 0.6477)
			(end -0.2794 -0.6477)
			(stroke
				(width 0)
				(type default)
			)
			(fill no)
			(layer "B.Fab")
		)
		(pad "1" smd custom
			(at 0 -0.2794 180)
			(size 0.0762 0.0762)
			(layers "B.Cu" "B.Mask" "B.Paste")
			(net "GB_VDDA")
			(options
				(clearance outline)
				(anchor circle)
			)
			(primitives
				(gr_poly
					(pts
						(arc
							(start 0.1524 0.127)
							(mid 0.137521 0.162921)
							(end 0.1016 0.1778)
						)
						(arc
							(start -0.1016 0.1778)
							(mid -0.137521 0.162921)
							(end -0.1524 0.127)
						)
						(arc
							(start -0.1524 -0.127)
							(mid -0.137521 -0.162921)
							(end -0.1016 -0.1778)
						)
						(arc
							(start 0.1016 -0.1778)
							(mid 0.137521 -0.162921)
							(end 0.1524 -0.127)
						)
					)
					(width 0)
					(fill yes)
				)
			)
		)
		(pad "2" smd custom
			(at 0 0.2794 180)
			(size 0.0762 0.0762)
			(layers "B.Cu" "B.Mask" "B.Paste")
			(net "GND")
			(options
				(clearance outline)
				(anchor circle)
			)
			(primitives
				(gr_poly
					(pts
						(arc
							(start 0.1524 0.127)
							(mid 0.137521 0.162921)
							(end 0.1016 0.1778)
						)
						(arc
							(start -0.1016 0.1778)
							(mid -0.137521 0.162921)
							(end -0.1524 0.127)
						)
						(arc
							(start -0.1524 -0.127)
							(mid -0.137521 -0.162921)
							(end -0.1016 -0.1778)
						)
						(arc
							(start 0.1016 -0.1778)
							(mid 0.137521 -0.162921)
							(end 0.1524 -0.127)
						)
					)
					(width 0)
					(fill yes)
				)
			)
		)
	)
	(footprint ""
		(layer "B.Cu")
		(at 93.30436 -64.04356)
		(property "Reference" "C193"
			(at 0 0 0)
			(layer "B.SilkS")
			(hide yes)
			(effects
				(font
					(size 1.27 1.27)
				)
				(justify mirror)
			)
		)
		(property "Value" "SC10U6D3V2MX-GP-U"
			(at 1.524 -1.905 0)
			(unlocked yes)
			(layer "B.Fab")
			(hide yes)
			(effects
				(font
					(size 1.016 1.016)
					(thickness 0.1524)
				)
				(justify mirror)
			)
		)
		(property "Device Type" "C402-TO0D2H28"
			(at 1.524 -3.429 0)
			(unlocked yes)
			(layer "B.Fab")
			(hide yes)
			(effects
				(font
					(size 1.016 1.016)
					(thickness 0.1524)
				)
				(justify mirror)
			)
		)
		(duplicate_pad_numbers_are_jumpers no)
		(fp_rect
			(start 0.4826 0.889)
			(end -0.4826 -0.889)
			(stroke
				(width 0)
				(type default)
			)
			(fill no)
			(layer "B.CrtYd")
		)
		(fp_rect
			(start 0.4826 0.889)
			(end -0.4826 -0.889)
			(stroke
				(width 0)
				(type default)
			)
			(fill no)
			(layer "B.Fab")
		)
		(pad "1" smd custom
			(at 0 -0.4572 180)
			(size 0.1524 0.1524)
			(layers "B.Cu" "B.Mask" "B.Paste")
			(net "XTAL_VDDA18")
			(options
				(clearance outline)
				(anchor circle)
			)
			(primitives
				(gr_poly
					(pts
						(arc
							(start -0.254 -0.3048)
							(mid -0.325842 -0.275042)
							(end -0.3556 -0.2032)
						)
						(arc
							(start -0.3556 0.2032)
							(mid -0.325842 0.275042)
							(end -0.254 0.3048)
						)
						(arc
							(start 0.254 0.3048)
							(mid 0.325842 0.275042)
							(end 0.3556 0.2032)
						)
						(arc
							(start 0.3556 -0.2032)
							(mid 0.325842 -0.275042)
							(end 0.254 -0.3048)
						)
					)
					(width 0)
					(fill yes)
				)
			)
		)
		(pad "2" smd custom
			(at 0 0.4572 180)
			(size 0.1524 0.1524)
			(layers "B.Cu" "B.Mask" "B.Paste")
			(net "GND")
			(options
				(clearance outline)
				(anchor circle)
			)
			(primitives
				(gr_poly
					(pts
						(arc
							(start -0.254 -0.3048)
							(mid -0.325842 -0.275042)
							(end -0.3556 -0.2032)
						)
						(arc
							(start -0.3556 0.2032)
							(mid -0.325842 0.275042)
							(end -0.254 0.3048)
						)
						(arc
							(start 0.254 0.3048)
							(mid 0.325842 0.275042)
							(end 0.3556 0.2032)
						)
						(arc
							(start 0.3556 -0.2032)
							(mid 0.325842 -0.275042)
							(end 0.254 -0.3048)
						)
					)
					(width 0)
					(fill yes)
				)
			)
		)
	)
	(footprint ""
		(layer "B.Cu")
		(at 154.108404 -59.677808 -90)
		(property "Reference" "C358"
			(at 0 0 90)
			(layer "B.SilkS")
			(hide yes)
			(effects
				(font
					(size 1.27 1.27)
				)
				(justify mirror)
			)
		)
		(property "Value" "SCD1U16V2KX-3GP"
			(at -1.1811 -2.7051 270)
			(unlocked yes)
			(layer "B.Fab")
			(hide yes)
			(effects
				(font
					(size 1.016 1.016)
					(thickness 0.1524)
				)
				(justify mirror)
			)
		)
		(property "Device Type" "C402H22"
			(at -1.1811 -4.2291 270)
			(unlocked yes)
			(layer "B.Fab")
			(hide yes)
			(effects
				(font
					(size 1.016 1.016)
					(thickness 0.1524)
				)
				(justify mirror)
			)
		)
		(duplicate_pad_numbers_are_jumpers no)
		(fp_rect
			(start 0.4318 0.9525)
			(end -0.4318 -0.9525)
			(stroke
				(width 0)
				(type default)
			)
			(fill no)
			(layer "B.CrtYd")
		)
		(fp_rect
			(start 0.4318 0.9525)
			(end -0.4318 -0.9525)
			(stroke
				(width 0)
				(type default)
			)
			(fill no)
			(layer "B.Fab")
		)
		(pad "1" smd custom
			(at 0 -0.4445 90)
			(size 0.1524 0.1524)
			(layers "B.Cu" "B.Mask" "B.Paste")
			(net "SYS_PLL_VDD")
			(options
				(clearance outline)
				(anchor circle)
			)
			(primitives
				(gr_poly
					(pts
						(arc
							(start 0.3048 0.2032)
							(mid 0.275042 0.275042)
							(end 0.2032 0.3048)
						)
						(arc
							(start -0.2032 0.3048)
							(mid -0.275042 0.275042)
							(end -0.3048 0.2032)
						)
						(arc
							(start -0.3048 -0.2032)
							(mid -0.275042 -0.275042)
							(end -0.2032 -0.3048)
						)
						(arc
							(start 0.2032 -0.3048)
							(mid 0.275042 -0.275042)
							(end 0.3048 -0.2032)
						)
					)
					(width 0)
					(fill yes)
				)
			)
		)
		(pad "2" smd custom
			(at 0 0.4445 90)
			(size 0.1524 0.1524)
			(layers "B.Cu" "B.Mask" "B.Paste")
			(net "GND")
			(options
				(clearance outline)
				(anchor circle)
			)
			(primitives
				(gr_poly
					(pts
						(arc
							(start 0.3048 0.2032)
							(mid 0.275042 0.275042)
							(end 0.2032 0.3048)
						)
						(arc
							(start -0.2032 0.3048)
							(mid -0.275042 0.275042)
							(end -0.3048 0.2032)
						)
						(arc
							(start -0.3048 -0.2032)
							(mid -0.275042 -0.275042)
							(end -0.2032 -0.3048)
						)
						(arc
							(start 0.2032 -0.3048)
							(mid 0.275042 -0.275042)
							(end 0.3048 -0.2032)
						)
					)
					(width 0)
					(fill yes)
				)
			)
		)
	)
	(footprint ""
		(layer "B.Cu")
		(at 197.231 -24.257 180)
		(property "Reference" "LED1"
			(at 0 0 0)
			(layer "B.SilkS")
			(hide yes)
			(effects
				(font
					(size 1.27 1.27)
				)
				(justify mirror)
			)
		)
		(property "Value" "LED-YG-51-GP"
			(at 2.6924 -1.4224 180)
			(unlocked yes)
			(layer "B.Fab")
			(hide yes)
			(effects
				(font
					(size 1.016 1.016)
					(thickness 0.1524)
				)
				(justify mirror)
			)
		)
		(property "Device Type" "LED1608AKH40"
			(at 2.6924 -2.9464 180)
			(unlocked yes)
			(layer "B.Fab")
			(hide yes)
			(effects
				(font
					(size 1.016 1.016)
					(thickness 0.1524)
				)
				(justify mirror)
			)
		)
		(duplicate_pad_numbers_are_jumpers no)
		(fp_line
			(start 0.7493 1.651)
			(end 0.7493 1.1811)
			(stroke
				(width 0.3302)
				(type default)
			)
			(layer "B.SilkS")
		)
		(fp_line
			(start 0.6604 1.3716)
			(end 0.6604 -1.3716)
			(stroke
				(width 0.1524)
				(type default)
			)
			(layer "B.SilkS")
		)
		(fp_line
			(start 0.6604 -1.3716)
			(end -0.6604 -1.3716)
			(stroke
				(width 0.1524)
				(type default)
			)
			(layer "B.SilkS")
		)
		(fp_line
			(start 0.5969 1.5494)
			(end -0.5842 1.5494)
			(stroke
				(width 0.508)
				(type default)
			)
			(layer "B.SilkS")
		)
		(fp_line
			(start -0.6604 1.3716)
			(end 0.6604 1.3716)
			(stroke
				(width 0.1524)
				(type default)
			)
			(layer "B.SilkS")
		)
		(fp_line
			(start -0.6604 -1.3716)
			(end -0.6604 1.3716)
			(stroke
				(width 0.1524)
				(type default)
			)
			(layer "B.SilkS")
		)
		(fp_line
			(start -0.7493 1.651)
			(end -0.7493 1.1811)
			(stroke
				(width 0.3302)
				(type default)
			)
			(layer "B.SilkS")
		)
		(fp_rect
			(start 0.6223 1.3335)
			(end -0.6223 -1.3335)
			(stroke
				(width 0)
				(type default)
			)
			(fill no)
			(layer "B.CrtYd")
		)
		(fp_rect
			(start 0.6223 1.3335)
			(end -0.6223 -1.3335)
			(stroke
				(width 0)
				(type default)
			)
			(fill no)
			(layer "B.Fab")
		)
		(pad "A" smd custom
			(at 0 -0.762)
			(size 0.2159 0.2159)
			(layers "B.Cu" "B.Mask" "B.Paste")
			(net "SYS_HB_LED_R")
			(options
				(clearance outline)
				(anchor circle)
			)
			(primitives
				(gr_poly
					(pts
						(arc
							(start -0.3302 0.4318)
							(mid -0.402042 0.402042)
							(end -0.4318 0.3302)
						)
						(arc
							(start -0.4318 -0.3302)
							(mid -0.402042 -0.402042)
							(end -0.3302 -0.4318)
						)
						(arc
							(start 0.3302 -0.4318)
							(mid 0.402042 -0.402042)
							(end 0.4318 -0.3302)
						)
						(arc
							(start 0.4318 0.3302)
							(mid 0.402042 0.402042)
							(end 0.3302 0.4318)
						)
					)
					(width 0)
					(fill yes)
				)
			)
		)
		(pad "K" smd custom
			(at 0 0.762)
			(size 0.2159 0.2159)
			(layers "B.Cu" "B.Mask" "B.Paste")
			(net "SYS_HB_LED_D")
			(options
				(clearance outline)
				(anchor circle)
			)
			(primitives
				(gr_poly
					(pts
						(arc
							(start -0.3302 0.4318)
							(mid -0.402042 0.402042)
							(end -0.4318 0.3302)
						)
						(arc
							(start -0.4318 -0.3302)
							(mid -0.402042 -0.402042)
							(end -0.3302 -0.4318)
						)
						(arc
							(start 0.3302 -0.4318)
							(mid 0.402042 -0.402042)
							(end 0.4318 -0.3302)
						)
						(arc
							(start 0.4318 0.3302)
							(mid 0.402042 0.402042)
							(end 0.3302 0.4318)
						)
					)
					(width 0)
					(fill yes)
				)
			)
		)
	)
	(footprint ""
		(layer "B.Cu")
		(at 163.068 -64.008 -90)
		(property "Reference" "C367"
			(at 0 0 90)
			(layer "B.SilkS")
			(hide yes)
			(effects
				(font
					(size 1.27 1.27)
				)
				(justify mirror)
			)
		)
		(property "Value" "SC22U6D3V3MX-9-GP-U"
			(at 0 -2.8194 270)
			(unlocked yes)
			(layer "B.Fab")
			(hide yes)
			(effects
				(font
					(size 1.016 1.016)
					(thickness 0.1524)
				)
				(justify mirror)
			)
		)
		(property "Device Type" "C603H40"
			(at 0 -4.3434 270)
			(unlocked yes)
			(layer "B.Fab")
			(hide yes)
			(effects
				(font
					(size 1.016 1.016)
					(thickness 0.1524)
				)
				(justify mirror)
			)
		)
		(duplicate_pad_numbers_are_jumpers no)
		(fp_line
			(start -0.508 0)
			(end 0.508 0)
			(stroke
				(width 0.2032)
				(type default)
			)
			(layer "B.SilkS")
		)
		(fp_rect
			(start 0.5842 1.3335)
			(end -0.5842 -1.3335)
			(stroke
				(width 0)
				(type default)
			)
			(fill no)
			(layer "B.CrtYd")
		)
		(fp_rect
			(start 0.5842 1.3335)
			(end -0.5842 -1.3335)
			(stroke
				(width 0)
				(type default)
			)
			(fill no)
			(layer "B.Fab")
		)
		(pad "1" smd custom
			(at 0 -0.762 90)
			(size 0.2159 0.2159)
			(layers "B.Cu" "B.Mask" "B.Paste")
			(net "VDDA_SAS_REF_CLK")
			(options
				(clearance outline)
				(anchor circle)
			)
			(primitives
				(gr_poly
					(pts
						(arc
							(start -0.3302 0.4318)
							(mid -0.402042 0.402042)
							(end -0.4318 0.3302)
						)
						(arc
							(start -0.4318 -0.3302)
							(mid -0.402042 -0.402042)
							(end -0.3302 -0.4318)
						)
						(arc
							(start 0.3302 -0.4318)
							(mid 0.402042 -0.402042)
							(end 0.4318 -0.3302)
						)
						(arc
							(start 0.4318 0.3302)
							(mid 0.402042 0.402042)
							(end 0.3302 0.4318)
						)
					)
					(width 0)
					(fill yes)
				)
			)
		)
		(pad "2" smd custom
			(at 0 0.762 90)
			(size 0.2159 0.2159)
			(layers "B.Cu" "B.Mask" "B.Paste")
			(net "GND")
			(options
				(clearance outline)
				(anchor circle)
			)
			(primitives
				(gr_poly
					(pts
						(arc
							(start -0.3302 0.4318)
							(mid -0.402042 0.402042)
							(end -0.4318 0.3302)
						)
						(arc
							(start -0.4318 -0.3302)
							(mid -0.402042 -0.402042)
							(end -0.3302 -0.4318)
						)
						(arc
							(start 0.3302 -0.4318)
							(mid 0.402042 -0.402042)
							(end 0.4318 -0.3302)
						)
						(arc
							(start 0.4318 0.3302)
							(mid 0.402042 0.402042)
							(end 0.3302 0.4318)
						)
					)
					(width 0)
					(fill yes)
				)
			)
		)
	)
)
